(kicad_pcb
	(version 20240108)
	(generator "pcbnew")
	(generator_version "8.0")
	(general
		(thickness 1.62)
		(legacy_teardrops no)
	)
	(paper "A4")
	(title_block
		(title "Jetson Orin Baseboard")
		(date "2025-03-12")
		(rev "1.3.4")
		(company "Antmicro Ltd")
		(comment 1 "www.antmicro.com")
		(comment 9 "footprints 585-589 of 677")
	)
	(layers
		(0 "F.Cu" signal)
		(1 "In1.Cu" signal)
		(2 "In2.Cu" signal)
		(3 "In3.Cu" signal)
		(4 "In4.Cu" jumper)
		(5 "In5.Cu" signal)
		(6 "In6.Cu" signal)
		(31 "B.Cu" signal)
		(32 "B.Adhes" user "B.Adhesive")
		(33 "F.Adhes" user "F.Adhesive")
		(34 "B.Paste" user)
		(35 "F.Paste" user)
		(36 "B.SilkS" user "B.Silkscreen")
		(37 "F.SilkS" user "F.Silkscreen")
		(38 "B.Mask" user)
		(39 "F.Mask" user)
		(40 "Dwgs.User" user "User.Drawings")
		(41 "Cmts.User" user "User.Comments")
		(42 "Eco1.User" user "User.Eco1")
		(43 "Eco2.User" user "User.Eco2")
		(44 "Edge.Cuts" user)
		(45 "Margin" user)
		(46 "B.CrtYd" user "B.Courtyard")
		(47 "F.CrtYd" user "F.Courtyard")
		(48 "B.Fab" user)
		(49 "F.Fab" user)
	)
	(footprint "antmicro-footprints:R_0402_1005Metric"
		(layer "B.Cu")
		(at 72.3 106.2)
		(descr "Resistor SMD 0402")
		(tags "resistor SMD 0402")
		(property "Reference" "R79"
			(at -0.23 2.18 180)
			(layer "B.SilkS")
			(effects
				(font
					(size 0.7 0.7)
					(thickness 0.15)
				)
				(justify left bottom mirror)
			)
		)
		(property "Value" "R_0R_0402"
			(at 0 -1.4 180)
			(layer "B.Fab")
			(effects
				(font
					(size 0.7 0.7)
					(thickness 0.15)
				)
				(justify left bottom mirror)
			)
		)
		(property "Footprint" "antmicro-footprints:R_0402_1005Metric"
			(at 0 0 0)
			(layer "F.Fab")
			(hide yes)
			(effects
				(font
					(size 1.27 1.27)
					(thickness 0.15)
				)
			)
		)
		(property "Datasheet" "https://industrial.panasonic.com/cdbs/www-data/pdf/RDA0000/AOA0000C301.pdf"
			(at 0 0 0)
			(layer "F.Fab")
			(hide yes)
			(effects
				(font
					(size 1.27 1.27)
					(thickness 0.15)
				)
			)
		)
		(property "Author" "Antmicro"
			(at 0 0 0)
			(layer "B.Fab")
			(hide yes)
			(effects
				(font
					(size 1 1)
					(thickness 0.15)
				)
				(justify mirror)
			)
		)
		(property "Current" "1A"
			(at 0 0 0)
			(layer "B.Fab")
			(hide yes)
			(effects
				(font
					(size 1 1)
					(thickness 0.15)
				)
				(justify mirror)
			)
		)
		(property "License" "Apache-2.0"
			(at 0 0 0)
			(layer "B.Fab")
			(hide yes)
			(effects
				(font
					(size 1 1)
					(thickness 0.15)
				)
				(justify mirror)
			)
		)
		(property "MPN" "ERJ2GE0R00X"
			(at 0 0 0)
			(layer "B.Fab")
			(hide yes)
			(effects
				(font
					(size 1 1)
					(thickness 0.15)
				)
				(justify mirror)
			)
		)
		(property "Manufacturer" "Panasonic"
			(at 0 0 0)
			(layer "B.Fab")
			(hide yes)
			(effects
				(font
					(size 1 1)
					(thickness 0.15)
				)
				(justify mirror)
			)
		)
		(property "Tolerance" ""
			(at 0 0 0)
			(layer "B.Fab")
			(hide yes)
			(effects
				(font
					(size 1 1)
					(thickness 0.15)
				)
				(justify mirror)
			)
		)
		(property "Val" "0R"
			(at 0 0 0)
			(layer "B.Fab")
			(hide yes)
			(effects
				(font
					(size 1 1)
					(thickness 0.15)
				)
				(justify mirror)
			)
		)
		(sheetname "USB Debug, DP")
		(sheetfile "usb.kicad_sch")
		(attr smd exclude_from_pos_files exclude_from_bom dnp)
		(fp_rect
			(start -0.925 0.47)
			(end 0.925 -0.47)
			(stroke
				(width 0.05)
				(type default)
			)
			(fill none)
			(layer "B.CrtYd")
		)
		(fp_rect
			(start -0.5 0.25)
			(end 0.5 -0.25)
			(stroke
				(width 0.15)
				(type solid)
			)
			(fill none)
			(layer "B.Fab")
		)
		(fp_text user "License: Apache-2.0"
			(at -0.95 -5.169 180)
			(layer "B.Fab")
			(hide yes)
			(effects
				(font
					(size 0.7 0.7)
					(thickness 0.15)
				)
				(justify left bottom mirror)
			)
		)
		(fp_text user "${REFERENCE}"
			(at -0.95 -3.168 180)
			(layer "B.Fab")
			(hide yes)
			(effects
				(font
					(size 0.7 0.7)
					(thickness 0.15)
				)
				(justify left bottom mirror)
			)
		)
		(fp_text user "Author: Antmicro"
			(at -0.95 -4.169 180)
			(layer "B.Fab")
			(hide yes)
			(effects
				(font
					(size 0.7 0.7)
					(thickness 0.15)
				)
				(justify left bottom mirror)
			)
		)
		(pad "1" smd roundrect
			(at -0.48 0)
			(size 0.59 0.64)
			(layers "B.Cu" "B.Paste" "B.Mask")
			(roundrect_rratio 0.25)
			(net 295 "/USB Debug, DP/USBC0_CTL0")
			(pintype "passive")
		)
		(pad "2" smd roundrect
			(at 0.48 0)
			(size 0.59 0.64)
			(layers "B.Cu" "B.Paste" "B.Mask")
			(roundrect_rratio 0.25)
			(net 251 "SYS_SDA")
			(pintype "passive")
		)
	)
	(footprint "antmicro-footprints:R_0402_1005Metric"
		(layer "B.Cu")
		(at 58.9 79.95)
		(descr "Resistor SMD 0402")
		(tags "resistor SMD 0402")
		(property "Reference" "R256"
			(at 23.81 9.18 180)
			(layer "B.SilkS")
			(effects
				(font
					(size 0.7 0.7)
					(thickness 0.15)
				)
				(justify left bottom mirror)
			)
		)
		(property "Value" "R_1k_0402"
			(at 0 -1.4 180)
			(layer "B.Fab")
			(effects
				(font
					(size 0.7 0.7)
					(thickness 0.15)
				)
				(justify left bottom mirror)
			)
		)
		(property "Footprint" "antmicro-footprints:R_0402_1005Metric"
			(at 0 0 0)
			(layer "F.Fab")
			(hide yes)
			(effects
				(font
					(size 1.27 1.27)
					(thickness 0.15)
				)
			)
		)
		(property "Datasheet" "https://www.bourns.com/docs/product-datasheets/cr.pdf"
			(at 0 0 0)
			(layer "F.Fab")
			(hide yes)
			(effects
				(font
					(size 1.27 1.27)
					(thickness 0.15)
				)
			)
		)
		(property "Author" "Antmicro"
			(at 0 0 0)
			(layer "B.Fab")
			(hide yes)
			(effects
				(font
					(size 1 1)
					(thickness 0.15)
				)
				(justify mirror)
			)
		)
		(property "License" "Apache-2.0"
			(at 0 0 0)
			(layer "B.Fab")
			(hide yes)
			(effects
				(font
					(size 1 1)
					(thickness 0.15)
				)
				(justify mirror)
			)
		)
		(property "MPN" "CR0402-FX-1001GLF"
			(at 0 0 0)
			(layer "B.Fab")
			(hide yes)
			(effects
				(font
					(size 1 1)
					(thickness 0.15)
				)
				(justify mirror)
			)
		)
		(property "Manufacturer" "Bourns"
			(at 0 0 0)
			(layer "B.Fab")
			(hide yes)
			(effects
				(font
					(size 1 1)
					(thickness 0.15)
				)
				(justify mirror)
			)
		)
		(property "Tolerance" "1%"
			(at 0 0 0)
			(layer "B.Fab")
			(hide yes)
			(effects
				(font
					(size 1 1)
					(thickness 0.15)
				)
				(justify mirror)
			)
		)
		(property "Val" "1k"
			(at 0 0 0)
			(layer "B.Fab")
			(hide yes)
			(effects
				(font
					(size 1 1)
					(thickness 0.15)
				)
				(justify mirror)
			)
		)
		(sheetname "Supply")
		(sheetfile "supply.kicad_sch")
		(attr smd)
		(fp_rect
			(start -0.925 0.47)
			(end 0.925 -0.47)
			(stroke
				(width 0.05)
				(type default)
			)
			(fill none)
			(layer "B.CrtYd")
		)
		(fp_rect
			(start -0.5 0.25)
			(end 0.5 -0.25)
			(stroke
				(width 0.15)
				(type solid)
			)
			(fill none)
			(layer "B.Fab")
		)
		(fp_text user "${REFERENCE}"
			(at -0.95 -3.168 180)
			(layer "B.Fab")
			(hide yes)
			(effects
				(font
					(size 0.7 0.7)
					(thickness 0.15)
				)
				(justify left bottom mirror)
			)
		)
		(fp_text user "License: Apache-2.0"
			(at -0.95 -5.169 180)
			(layer "B.Fab")
			(hide yes)
			(effects
				(font
					(size 0.7 0.7)
					(thickness 0.15)
				)
				(justify left bottom mirror)
			)
		)
		(fp_text user "Author: Antmicro"
			(at -0.95 -4.169 180)
			(layer "B.Fab")
			(hide yes)
			(effects
				(font
					(size 0.7 0.7)
					(thickness 0.15)
				)
				(justify left bottom mirror)
			)
		)
		(pad "1" smd roundrect
			(at -0.48 0)
			(size 0.59 0.64)
			(layers "B.Cu" "B.Paste" "B.Mask")
			(roundrect_rratio 0.25)
			(net 530 "Net-(R256-Pad1)")
			(pintype "passive")
		)
		(pad "2" smd roundrect
			(at 0.48 0)
			(size 0.59 0.64)
			(layers "B.Cu" "B.Paste" "B.Mask")
			(roundrect_rratio 0.25)
			(net 117 "3V3_STDB")
			(pintype "passive")
		)
	)
	(footprint "antmicro-footprints:R_0402_1005Metric"
		(layer "B.Cu")
		(at 109.1 112 -90)
		(descr "Resistor SMD 0402")
		(tags "resistor SMD 0402")
		(property "Reference" "R60"
			(at 0.75 -0.45 90)
			(layer "B.SilkS")
			(effects
				(font
					(size 0.7 0.7)
					(thickness 0.15)
				)
				(justify left bottom mirror)
			)
		)
		(property "Value" "R_10k_0402"
			(at 0 -1.4 90)
			(layer "B.Fab")
			(effects
				(font
					(size 0.7 0.7)
					(thickness 0.15)
				)
				(justify left bottom mirror)
			)
		)
		(property "Footprint" "antmicro-footprints:R_0402_1005Metric"
			(at 0 0 -90)
			(layer "F.Fab")
			(hide yes)
			(effects
				(font
					(size 1.27 1.27)
					(thickness 0.15)
				)
			)
		)
		(property "Datasheet" "https://www.bourns.com/docs/product-datasheets/cr.pdf"
			(at 0 0 -90)
			(layer "F.Fab")
			(hide yes)
			(effects
				(font
					(size 1.27 1.27)
					(thickness 0.15)
				)
			)
		)
		(property "Author" "Antmicro"
			(at -2.9 221.1 0)
			(layer "B.Fab")
			(hide yes)
			(effects
				(font
					(size 1 1)
					(thickness 0.15)
				)
				(justify mirror)
			)
		)
		(property "License" "Apache-2.0"
			(at -2.9 221.1 0)
			(layer "B.Fab")
			(hide yes)
			(effects
				(font
					(size 1 1)
					(thickness 0.15)
				)
				(justify mirror)
			)
		)
		(property "MPN" "CR0402-FX-1002GLF"
			(at -2.9 221.1 0)
			(layer "B.Fab")
			(hide yes)
			(effects
				(font
					(size 1 1)
					(thickness 0.15)
				)
				(justify mirror)
			)
		)
		(property "Manufacturer" "Bourns"
			(at -2.9 221.1 0)
			(layer "B.Fab")
			(hide yes)
			(effects
				(font
					(size 1 1)
					(thickness 0.15)
				)
				(justify mirror)
			)
		)
		(property "Tolerance" "1%"
			(at -2.9 221.1 0)
			(layer "B.Fab")
			(hide yes)
			(effects
				(font
					(size 1 1)
					(thickness 0.15)
				)
				(justify mirror)
			)
		)
		(property "Val" "10k"
			(at -2.9 221.1 0)
			(layer "B.Fab")
			(hide yes)
			(effects
				(font
					(size 1 1)
					(thickness 0.15)
				)
				(justify mirror)
			)
		)
		(sheetname "USB3")
		(sheetfile "usb3.kicad_sch")
		(attr smd exclude_from_pos_files exclude_from_bom dnp)
		(fp_rect
			(start -0.925 0.47)
			(end 0.925 -0.47)
			(stroke
				(width 0.05)
				(type default)
			)
			(fill none)
			(layer "B.CrtYd")
		)
		(fp_rect
			(start -0.5 0.25)
			(end 0.5 -0.25)
			(stroke
				(width 0.15)
				(type solid)
			)
			(fill none)
			(layer "B.Fab")
		)
		(fp_text user "Author: Antmicro"
			(at -0.95 -4.169 90)
			(layer "B.Fab")
			(hide yes)
			(effects
				(font
					(size 0.7 0.7)
					(thickness 0.15)
				)
				(justify left bottom mirror)
			)
		)
		(fp_text user "${REFERENCE}"
			(at -0.95 -3.168 90)
			(layer "B.Fab")
			(hide yes)
			(effects
				(font
					(size 0.7 0.7)
					(thickness 0.15)
				)
				(justify left bottom mirror)
			)
		)
		(fp_text user "License: Apache-2.0"
			(at -0.95 -5.169 90)
			(layer "B.Fab")
			(hide yes)
			(effects
				(font
					(size 0.7 0.7)
					(thickness 0.15)
				)
				(justify left bottom mirror)
			)
		)
		(pad "1" smd roundrect
			(at -0.48 0 270)
			(size 0.59 0.64)
			(layers "B.Cu" "B.Paste" "B.Mask")
			(roundrect_rratio 0.25)
			(net 632 "Net-(Q19-G)")
			(pintype "passive")
		)
		(pad "2" smd roundrect
			(at 0.48 0 270)
			(size 0.59 0.64)
			(layers "B.Cu" "B.Paste" "B.Mask")
			(roundrect_rratio 0.25)
			(net 270 "/USB3/USBC1_VBUS")
			(pintype "passive")
		)
	)
	(footprint "antmicro-footprints:TP_SMD_0.75mm"
		(layer "B.Cu")
		(at 86.5 102.3008 180)
		(property "Reference" "TP22"
			(at -0.93 0.6808 0)
			(layer "B.SilkS")
			(effects
				(font
					(size 0.7 0.7)
					(thickness 0.15)
				)
				(justify left bottom mirror)
			)
		)
		(property "Value" "TP_0.75mm_SMD"
			(at 0 -1.2 0)
			(layer "B.Fab")
			(effects
				(font
					(size 0.7 0.7)
					(thickness 0.15)
				)
				(justify left bottom mirror)
			)
		)
		(property "Footprint" "antmicro-footprints:TP_SMD_0.75mm"
			(at 0 0 180)
			(layer "F.Fab")
			(hide yes)
			(effects
				(font
					(size 1.27 1.27)
					(thickness 0.15)
				)
			)
		)
		(property "Author" "Antmicro"
			(at 173 204.6016 0)
			(layer "B.Fab")
			(hide yes)
			(effects
				(font
					(size 1 1)
					(thickness 0.15)
				)
				(justify mirror)
			)
		)
		(property "License" "Apache-2.0"
			(at 173 204.6016 0)
			(layer "B.Fab")
			(hide yes)
			(effects
				(font
					(size 1 1)
					(thickness 0.15)
				)
				(justify mirror)
			)
		)
		(property "MPN" ""
			(at 173 204.6016 0)
			(layer "B.Fab")
			(hide yes)
			(effects
				(font
					(size 1 1)
					(thickness 0.15)
				)
				(justify mirror)
			)
		)
		(property "Manufacturer" ""
			(at 173 204.6016 0)
			(layer "B.Fab")
			(hide yes)
			(effects
				(font
					(size 1 1)
					(thickness 0.15)
				)
				(justify mirror)
			)
		)
		(sheetname "HDMI")
		(sheetfile "hdmi.kicad_sch")
		(attr exclude_from_pos_files exclude_from_bom)
		(fp_circle
			(center 0 0)
			(end 0.475 0)
			(stroke
				(width 0.05)
				(type default)
			)
			(fill none)
			(layer "B.CrtYd")
		)
		(fp_text user "License: Apache-2.0"
			(at -0.4 -5.101 0)
			(layer "B.Fab")
			(hide yes)
			(effects
				(font
					(size 0.7 0.7)
					(thickness 0.15)
				)
				(justify left bottom mirror)
			)
		)
		(fp_text user "${REFERENCE}"
			(at -0.4 -2.7 0)
			(layer "B.Fab")
			(hide yes)
			(effects
				(font
					(size 0.7 0.7)
					(thickness 0.15)
				)
				(justify left bottom mirror)
			)
		)
		(fp_text user "Author: Antmicro"
			(at -0.4 -3.901 0)
			(layer "B.Fab")
			(hide yes)
			(effects
				(font
					(size 0.7 0.7)
					(thickness 0.15)
				)
				(justify left bottom mirror)
			)
		)
		(pad "1" smd circle
			(at 0 0 180)
			(size 0.75 0.75)
			(layers "B.Cu" "B.Mask")
			(net 703 "/HDMI/HDMI_HPD")
			(pinfunction "1")
			(pintype "passive")
		)
	)
	(footprint "antmicro-footprints:C_0603_1608Metric"
		(layer "B.Cu")
		(at 76.26 79.55 -90)
		(descr "Capacitor SMD 0603")
		(tags "capacitor 0603")
		(property "Reference" "C134"
			(at -1.45 -1.54 90)
			(layer "B.SilkS")
			(effects
				(font
					(size 0.7 0.7)
					(thickness 0.15)
				)
				(justify left bottom mirror)
			)
		)
		(property "Value" "C_10u_25V_0603"
			(at 0 -1.6 90)
			(layer "B.Fab")
			(effects
				(font
					(size 0.7 0.7)
					(thickness 0.15)
				)
				(justify left bottom mirror)
			)
		)
		(property "Footprint" "antmicro-footprints:C_0603_1608Metric"
			(at 0 0 -90)
			(layer "F.Fab")
			(hide yes)
			(effects
				(font
					(size 1.27 1.27)
					(thickness 0.15)
				)
			)
		)
		(property "Datasheet" "https://product.tdk.com/en/search/capacitor/ceramic/mlcc/info?part_no=C1608X5R1E106M080AC"
			(at 0 0 -90)
			(layer "F.Fab")
			(hide yes)
			(effects
				(font
					(size 1.27 1.27)
					(thickness 0.15)
				)
			)
		)
		(property "Author" "Antmicro"
			(at -3.29 155.81 0)
			(layer "B.Fab")
			(hide yes)
			(effects
				(font
					(size 1 1)
					(thickness 0.15)
				)
				(justify mirror)
			)
		)
		(property "Dielectric" ""
			(at -3.29 155.81 0)
			(layer "B.Fab")
			(hide yes)
			(effects
				(font
					(size 1 1)
					(thickness 0.15)
				)
				(justify mirror)
			)
		)
		(property "License" "Apache-2.0"
			(at -3.29 155.81 0)
			(layer "B.Fab")
			(hide yes)
			(effects
				(font
					(size 1 1)
					(thickness 0.15)
				)
				(justify mirror)
			)
		)
		(property "MPN" "C1608X5R1E106M080AC"
			(at -3.29 155.81 0)
			(layer "B.Fab")
			(hide yes)
			(effects
				(font
					(size 1 1)
					(thickness 0.15)
				)
				(justify mirror)
			)
		)
		(property "Manufacturer" "TDK"
			(at -3.29 155.81 0)
			(layer "B.Fab")
			(hide yes)
			(effects
				(font
					(size 1 1)
					(thickness 0.15)
				)
				(justify mirror)
			)
		)
		(property "Val" "10u"
			(at -3.29 155.81 0)
			(layer "B.Fab")
			(hide yes)
			(effects
				(font
					(size 1 1)
					(thickness 0.15)
				)
				(justify mirror)
			)
		)
		(property "Voltage" "25V"
			(at -3.29 155.81 0)
			(layer "B.Fab")
			(hide yes)
			(effects
				(font
					(size 1 1)
					(thickness 0.15)
				)
				(justify mirror)
			)
		)
		(sheetname "Supply")
		(sheetfile "supply.kicad_sch")
		(attr smd)
		(fp_line
			(start 0.15 0.4)
			(end -0.15 0.4)
			(stroke
				(width 0.15)
				(type solid)
			)
			(layer "B.SilkS")
		)
		(fp_line
			(start 0.15 -0.4)
			(end -0.15 -0.4)
			(stroke
				(width 0.15)
				(type solid)
			)
			(layer "B.SilkS")
		)
		(fp_rect
			(start -1.25 0.65)
			(end 1.25 -0.65)
			(stroke
				(width 0.05)
				(type solid)
			)
			(fill none)
			(layer "B.CrtYd")
		)
		(fp_rect
			(start -0.8 0.4)
			(end 0.8 -0.4)
			(stroke
				(width 0.15)
				(type solid)
			)
			(fill none)
			(layer "B.Fab")
		)
		(fp_text user "License: Apache-2.0"
			(at -1.682 -5.895 90)
			(layer "B.Fab")
			(hide yes)
			(effects
				(font
					(size 0.7 0.7)
					(thickness 0.15)
				)
				(justify left bottom mirror)
			)
		)
		(fp_text user "Author: Antmicro"
			(at -1.682 -4.894 90)
			(layer "B.Fab")
			(hide yes)
			(effects
				(font
					(size 0.7 0.7)
					(thickness 0.15)
				)
				(justify left bottom mirror)
			)
		)
		(fp_text user "${REFERENCE}"
			(at -1.682 -3.895 90)
			(layer "B.Fab")
			(hide yes)
			(effects
				(font
					(size 0.7 0.7)
					(thickness 0.15)
				)
				(justify left bottom mirror)
			)
		)
		(pad "1" smd roundrect
			(at -0.7 0 270)
			(size 0.8 1)
			(layers "B.Cu" "B.Paste" "B.Mask")
			(roundrect_rratio 0.2)
			(net 1 "GND")
			(pintype "passive")
		)
		(pad "2" smd roundrect
			(at 0.7 0 270)
			(size 0.8 1)
			(layers "B.Cu" "B.Paste" "B.Mask")
			(roundrect_rratio 0.2)
			(net 115 "VCC")
			(pintype "passive")
		)
	)
)
